# S9S_MB_2U (Grand Teton) — schematic netlist excerpt (pin names and nets, part order shuffled) for the footprints in the layout excerpt that follows; sources: Cadence DE-HDL packaged netlist, KiCad conversion of 03242023_DA0F0TMBIJ0_F0T_Motherboard_J_brd_V01_OCP.brd

R1229  Q_RES  240 1% EMPTY  pkg 0402LF  page 119 : A = PVNN_TERM_CPU1 ; B = PUD_XTAL_CPU1_MODE0
R771  Q_RES  1K 1% CHIP  pkg 0402LF  page 131 : A = JTAG_DBP_PCH_DEBUG_CONSENT_N ; B = FM_PCH_CONSENT_STRAP_N

(kicad_pcb
	(version 20260206)
	(generator "pcbnew")
	(generator_version "10.0")
	(general
		(thickness 1.6)
		(legacy_teardrops no)
	)
	(paper "A4")
	(title_block
		(title "03242023_DA0F0TMBIJ0_F0T_Motherboard_J_brd_V01_OCP.brd")
		(comment 1 "Grand Teton / footprints 1740-1741 of 6105")
	)
	(layers
		(0 "F.Cu" signal "TOP")
		(4 "In1.Cu" signal "GND")
		(6 "In2.Cu" signal "IN1")
		(8 "In3.Cu" signal "GND1")
		(10 "In4.Cu" signal "IN2")
		(12 "In5.Cu" signal "GND2")
		(14 "In6.Cu" signal "IN3")
		(16 "In7.Cu" signal "GND3")
		(18 "In8.Cu" signal "VCC")
		(20 "In9.Cu" signal "VCC1")
		(22 "In10.Cu" signal "GND4")
		(24 "In11.Cu" signal "IN4")
		(26 "In12.Cu" signal "GND5")
		(28 "In13.Cu" signal "IN5")
		(30 "In14.Cu" signal "GND6")
		(32 "In15.Cu" signal "IN6")
		(34 "In16.Cu" signal "GND7")
		(2 "B.Cu" signal "BOTTOM")
		(9 "F.Adhes" user "F.Adhesive")
		(11 "B.Adhes" user "B.Adhesive")
		(13 "F.Paste" user "Package Geometry/Pastemask Top")
		(15 "B.Paste" user "Package Geometry/Pastemask Bottom")
		(5 "F.SilkS" user "Ref Des/Silkscreen Top")
		(7 "B.SilkS" user "Ref Des/Silkscreen Bottom")
		(1 "F.Mask" user "Board Geometry/Soldermask Top")
		(3 "B.Mask" user "Board Geometry/Soldermask Bottom")
		(17 "Dwgs.User" user "User.Drawings")
		(19 "Cmts.User" user "User.Comments")
		(21 "Eco1.User" user "User.Eco1")
		(23 "Eco2.User" user "User.Eco2")
		(25 "Edge.Cuts" user "Board Geometry/Outline")
		(27 "Margin" user)
		(31 "F.CrtYd" user "Package Geometry/Place Bound Top")
		(29 "B.CrtYd" user "Package Geometry/Place Bound Bottom")
		(35 "F.Fab" user "Ref Des/Assembly Top")
		(33 "B.Fab" user "Ref Des/Assembly Bottom")
	)
	(footprint ""
		(layer "F.Cu")
		(at 193.95948 -349.367348 180)
		(property "Reference" "R1229"
			(at 0 0 180)
			(layer "F.SilkS")
			(hide yes)
			(effects
				(font
					(size 1.27 1.27)
				)
			)
		)
		(property "Value" ""
			(at 0 0 180)
			(layer "F.Fab")
			(effects
				(font
					(size 1.27 1.27)
				)
			)
		)
		(duplicate_pad_numbers_are_jumpers no)
		(fp_line
			(start 0.7874 0.4064)
			(end -0.7874 0.4064)
			(stroke
				(width 0.1524)
				(type default)
			)
			(layer "F.SilkS")
		)
		(fp_line
			(start 0.7874 -0.4064)
			(end 0.7874 0.4064)
			(stroke
				(width 0.1524)
				(type default)
			)
			(layer "F.SilkS")
		)
		(fp_line
			(start -0.7874 0.4064)
			(end -0.7874 -0.4064)
			(stroke
				(width 0.1524)
				(type default)
			)
			(layer "F.SilkS")
		)
		(fp_line
			(start -0.7874 -0.4064)
			(end 0.7874 -0.4064)
			(stroke
				(width 0.1524)
				(type default)
			)
			(layer "F.SilkS")
		)
		(fp_line
			(start 0.67945 0.3048)
			(end 0.120396 0.3048)
			(stroke
				(width 0.1)
				(type default)
			)
			(layer "F.Fab")
		)
		(fp_line
			(start 0.67945 -0.3048)
			(end 0.67945 0.3048)
			(stroke
				(width 0.1)
				(type default)
			)
			(layer "F.Fab")
		)
		(fp_line
			(start 0.12065 -0.2794)
			(end 0.12065 -0.3048)
			(stroke
				(width 0.1)
				(type default)
			)
			(layer "F.Fab")
		)
		(fp_line
			(start 0.12065 -0.3048)
			(end 0.67945 -0.3048)
			(stroke
				(width 0.1)
				(type default)
			)
			(layer "F.Fab")
		)
		(fp_line
			(start 0.120396 0.3048)
			(end 0.120396 0.2794)
			(stroke
				(width 0.1)
				(type default)
			)
			(layer "F.Fab")
		)
		(fp_line
			(start 0.120396 0.2794)
			(end -0.12065 0.2794)
			(stroke
				(width 0.1)
				(type default)
			)
			(layer "F.Fab")
		)
		(fp_line
			(start -0.12065 0.3048)
			(end -0.67945 0.3048)
			(stroke
				(width 0.1)
				(type default)
			)
			(layer "F.Fab")
		)
		(fp_line
			(start -0.12065 0.2794)
			(end -0.12065 0.3048)
			(stroke
				(width 0.1)
				(type default)
			)
			(layer "F.Fab")
		)
		(fp_line
			(start -0.12065 -0.2794)
			(end 0.12065 -0.2794)
			(stroke
				(width 0.1)
				(type default)
			)
			(layer "F.Fab")
		)
		(fp_line
			(start -0.12065 -0.305054)
			(end -0.12065 -0.2794)
			(stroke
				(width 0.1)
				(type default)
			)
			(layer "F.Fab")
		)
		(fp_line
			(start -0.67945 0.3048)
			(end -0.67945 -0.305054)
			(stroke
				(width 0.1)
				(type default)
			)
			(layer "F.Fab")
		)
		(fp_line
			(start -0.67945 -0.305054)
			(end -0.12065 -0.305054)
			(stroke
				(width 0.1)
				(type default)
			)
			(layer "F.Fab")
		)
		(pad "1" smd circle
			(at -0.40005 0 180)
			(size 0 0)
			(layers "F.Cu" "F.Mask" "F.Paste")
			(net "PVNN_TERM_CPU1")
		)
		(pad "2" smd circle
			(at 0.40005 0 180)
			(size 0 0)
			(layers "F.Cu" "F.Mask" "F.Paste")
			(net "PUD_XTAL_CPU1_MODE0")
		)
	)
	(footprint ""
		(layer "F.Cu")
		(at 385.716272 -60.735464 180)
		(property "Reference" "R771"
			(at 0 0 180)
			(layer "F.SilkS")
			(hide yes)
			(effects
				(font
					(size 1.27 1.27)
				)
			)
		)
		(property "Value" ""
			(at 0 0 180)
			(layer "F.Fab")
			(effects
				(font
					(size 1.27 1.27)
				)
			)
		)
		(duplicate_pad_numbers_are_jumpers no)
		(fp_line
			(start 0.7874 0.4064)
			(end -0.7874 0.4064)
			(stroke
				(width 0.1524)
				(type default)
			)
			(layer "F.SilkS")
		)
		(fp_line
			(start 0.7874 -0.4064)
			(end 0.7874 0.4064)
			(stroke
				(width 0.1524)
				(type default)
			)
			(layer "F.SilkS")
		)
		(fp_line
			(start -0.7874 0.4064)
			(end -0.7874 -0.4064)
			(stroke
				(width 0.1524)
				(type default)
			)
			(layer "F.SilkS")
		)
		(fp_line
			(start -0.7874 -0.4064)
			(end 0.7874 -0.4064)
			(stroke
				(width 0.1524)
				(type default)
			)
			(layer "F.SilkS")
		)
		(fp_line
			(start 0.67945 0.3048)
			(end 0.120396 0.3048)
			(stroke
				(width 0.1)
				(type default)
			)
			(layer "F.Fab")
		)
		(fp_line
			(start 0.67945 -0.3048)
			(end 0.67945 0.3048)
			(stroke
				(width 0.1)
				(type default)
			)
			(layer "F.Fab")
		)
		(fp_line
			(start 0.12065 -0.2794)
			(end 0.12065 -0.3048)
			(stroke
				(width 0.1)
				(type default)
			)
			(layer "F.Fab")
		)
		(fp_line
			(start 0.12065 -0.3048)
			(end 0.67945 -0.3048)
			(stroke
				(width 0.1)
				(type default)
			)
			(layer "F.Fab")
		)
		(fp_line
			(start 0.120396 0.3048)
			(end 0.120396 0.2794)
			(stroke
				(width 0.1)
				(type default)
			)
			(layer "F.Fab")
		)
		(fp_line
			(start 0.120396 0.2794)
			(end -0.12065 0.2794)
			(stroke
				(width 0.1)
				(type default)
			)
			(layer "F.Fab")
		)
		(fp_line
			(start -0.12065 0.3048)
			(end -0.67945 0.3048)
			(stroke
				(width 0.1)
				(type default)
			)
			(layer "F.Fab")
		)
		(fp_line
			(start -0.12065 0.2794)
			(end -0.12065 0.3048)
			(stroke
				(width 0.1)
				(type default)
			)
			(layer "F.Fab")
		)
		(fp_line
			(start -0.12065 -0.2794)
			(end 0.12065 -0.2794)
			(stroke
				(width 0.1)
				(type default)
			)
			(layer "F.Fab")
		)
		(fp_line
			(start -0.12065 -0.305054)
			(end -0.12065 -0.2794)
			(stroke
				(width 0.1)
				(type default)
			)
			(layer "F.Fab")
		)
		(fp_line
			(start -0.67945 0.3048)
			(end -0.67945 -0.305054)
			(stroke
				(width 0.1)
				(type default)
			)
			(layer "F.Fab")
		)
		(fp_line
			(start -0.67945 -0.305054)
			(end -0.12065 -0.305054)
			(stroke
				(width 0.1)
				(type default)
			)
			(layer "F.Fab")
		)
		(pad "1" smd circle
			(at -0.40005 0 180)
			(size 0 0)
			(layers "F.Cu" "F.Mask" "F.Paste")
			(net "JTAG_DBP_PCH_DEBUG_CONSENT_N")
		)
		(pad "2" smd circle
			(at 0.40005 0 180)
			(size 0 0)
			(layers "F.Cu" "F.Mask" "F.Paste")
			(net "FM_PCH_CONSENT_STRAP_N")
		)
	)
)
